(kicad_pcb
	(version 20260206)
	(generator "pcbnew")
	(generator_version "10.0")
	(general
		(thickness 1.6)
		(legacy_teardrops no)
	)
	(paper "A4")
	(title_block
		(title "12092022_DA0F0TMDCD0_F0T_Management_Board_D_brd_V3_OCP.brd")
		(comment 1 "Grand Teton / footprints 25-30 of 1440")
	)
	(layers
		(0 "F.Cu" signal "TOP")
		(4 "In1.Cu" signal "GND")
		(6 "In2.Cu" signal "IN1")
		(8 "In3.Cu" signal "GND1")
		(10 "In4.Cu" signal "IN2")
		(12 "In5.Cu" signal "VCC")
		(14 "In6.Cu" signal "VCC1")
		(16 "In7.Cu" signal "IN3")
		(18 "In8.Cu" signal "GND2")
		(20 "In9.Cu" signal "IN4")
		(22 "In10.Cu" signal "GND3")
		(2 "B.Cu" signal "BOTTOM")
		(9 "F.Adhes" user "F.Adhesive")
		(11 "B.Adhes" user "B.Adhesive")
		(13 "F.Paste" user "Package Geometry/Pastemask Top")
		(15 "B.Paste" user "Package Geometry/Pastemask Bottom")
		(5 "F.SilkS" user "Ref Des/Silkscreen Top")
		(7 "B.SilkS" user "Ref Des/Silkscreen Bottom")
		(1 "F.Mask" user "Board Geometry/Soldermask Top")
		(3 "B.Mask" user "Board Geometry/Soldermask Bottom")
		(17 "Dwgs.User" user "User.Drawings")
		(19 "Cmts.User" user "User.Comments")
		(21 "Eco1.User" user "User.Eco1")
		(23 "Eco2.User" user "User.Eco2")
		(25 "Edge.Cuts" user "Board Geometry/Outline")
		(27 "Margin" user)
		(31 "F.CrtYd" user "Package Geometry/Place Bound Top")
		(29 "B.CrtYd" user "Package Geometry/Place Bound Bottom")
		(35 "F.Fab" user "Ref Des/Assembly Top")
		(33 "B.Fab" user "Ref Des/Assembly Bottom")
	)
	(footprint ""
		(layer "F.Cu")
		(at 49.2125 -93.9165 -90)
		(property "Reference" "R291"
			(at 0 0 270)
			(layer "F.SilkS")
			(hide yes)
			(effects
				(font
					(size 1.27 1.27)
				)
			)
		)
		(property "Value" ""
			(at 0 0 270)
			(layer "F.Fab")
			(effects
				(font
					(size 1.27 1.27)
				)
			)
		)
		(duplicate_pad_numbers_are_jumpers no)
		(fp_line
			(start -0.7874 0.4064)
			(end -0.7874 -0.4064)
			(stroke
				(width 0.1524)
				(type default)
			)
			(layer "F.SilkS")
		)
		(fp_line
			(start 0.7874 0.4064)
			(end -0.7874 0.4064)
			(stroke
				(width 0.1524)
				(type default)
			)
			(layer "F.SilkS")
		)
		(fp_line
			(start -0.7874 -0.4064)
			(end 0.7874 -0.4064)
			(stroke
				(width 0.1524)
				(type default)
			)
			(layer "F.SilkS")
		)
		(fp_line
			(start 0.7874 -0.4064)
			(end 0.7874 0.4064)
			(stroke
				(width 0.1524)
				(type default)
			)
			(layer "F.SilkS")
		)
		(fp_line
			(start -0.67945 0.3048)
			(end -0.67945 -0.305054)
			(stroke
				(width 0.1)
				(type default)
			)
			(layer "F.Fab")
		)
		(fp_line
			(start -0.12065 0.3048)
			(end -0.67945 0.3048)
			(stroke
				(width 0.1)
				(type default)
			)
			(layer "F.Fab")
		)
		(fp_line
			(start 0.120396 0.3048)
			(end 0.120396 0.2794)
			(stroke
				(width 0.1)
				(type default)
			)
			(layer "F.Fab")
		)
		(fp_line
			(start 0.67945 0.3048)
			(end 0.120396 0.3048)
			(stroke
				(width 0.1)
				(type default)
			)
			(layer "F.Fab")
		)
		(fp_line
			(start -0.12065 0.2794)
			(end -0.12065 0.3048)
			(stroke
				(width 0.1)
				(type default)
			)
			(layer "F.Fab")
		)
		(fp_line
			(start 0.120396 0.2794)
			(end -0.12065 0.2794)
			(stroke
				(width 0.1)
				(type default)
			)
			(layer "F.Fab")
		)
		(fp_line
			(start -0.12065 -0.2794)
			(end 0.12065 -0.2794)
			(stroke
				(width 0.1)
				(type default)
			)
			(layer "F.Fab")
		)
		(fp_line
			(start 0.12065 -0.2794)
			(end 0.12065 -0.3048)
			(stroke
				(width 0.1)
				(type default)
			)
			(layer "F.Fab")
		)
		(fp_line
			(start 0.12065 -0.3048)
			(end 0.67945 -0.3048)
			(stroke
				(width 0.1)
				(type default)
			)
			(layer "F.Fab")
		)
		(fp_line
			(start 0.67945 -0.3048)
			(end 0.67945 0.3048)
			(stroke
				(width 0.1)
				(type default)
			)
			(layer "F.Fab")
		)
		(fp_line
			(start -0.67945 -0.305054)
			(end -0.12065 -0.305054)
			(stroke
				(width 0.1)
				(type default)
			)
			(layer "F.Fab")
		)
		(fp_line
			(start -0.12065 -0.305054)
			(end -0.12065 -0.2794)
			(stroke
				(width 0.1)
				(type default)
			)
			(layer "F.Fab")
		)
		(pad "1" smd circle
			(at -0.40005 0 270)
			(size 0 0)
			(layers "F.Cu" "F.Mask" "F.Paste")
			(net "P3V3_RGM")
		)
		(pad "2" smd circle
			(at 0.40005 0 270)
			(size 0 0)
			(layers "F.Cu" "F.Mask" "F.Paste")
			(net "RST_BMC_EXTRST_R1_N")
		)
	)
	(footprint ""
		(layer "F.Cu")
		(at 39.9034 -41.5036)
		(property "Reference" "R442"
			(at 0 0 0)
			(layer "F.SilkS")
			(hide yes)
			(effects
				(font
					(size 1.27 1.27)
				)
			)
		)
		(property "Value" ""
			(at 0 0 0)
			(layer "F.Fab")
			(effects
				(font
					(size 1.27 1.27)
				)
			)
		)
		(duplicate_pad_numbers_are_jumpers no)
		(fp_line
			(start -0.7874 -0.4064)
			(end 0.7874 -0.4064)
			(stroke
				(width 0.1524)
				(type default)
			)
			(layer "F.SilkS")
		)
		(fp_line
			(start -0.7874 0.4064)
			(end -0.7874 -0.4064)
			(stroke
				(width 0.1524)
				(type default)
			)
			(layer "F.SilkS")
		)
		(fp_line
			(start 0.7874 -0.4064)
			(end 0.7874 0.4064)
			(stroke
				(width 0.1524)
				(type default)
			)
			(layer "F.SilkS")
		)
		(fp_line
			(start 0.7874 0.4064)
			(end -0.7874 0.4064)
			(stroke
				(width 0.1524)
				(type default)
			)
			(layer "F.SilkS")
		)
		(fp_line
			(start -0.67945 -0.305054)
			(end -0.12065 -0.305054)
			(stroke
				(width 0.1)
				(type default)
			)
			(layer "F.Fab")
		)
		(fp_line
			(start -0.67945 0.3048)
			(end -0.67945 -0.305054)
			(stroke
				(width 0.1)
				(type default)
			)
			(layer "F.Fab")
		)
		(fp_line
			(start -0.12065 -0.305054)
			(end -0.12065 -0.2794)
			(stroke
				(width 0.1)
				(type default)
			)
			(layer "F.Fab")
		)
		(fp_line
			(start -0.12065 -0.2794)
			(end 0.12065 -0.2794)
			(stroke
				(width 0.1)
				(type default)
			)
			(layer "F.Fab")
		)
		(fp_line
			(start -0.12065 0.2794)
			(end -0.12065 0.3048)
			(stroke
				(width 0.1)
				(type default)
			)
			(layer "F.Fab")
		)
		(fp_line
			(start -0.12065 0.3048)
			(end -0.67945 0.3048)
			(stroke
				(width 0.1)
				(type default)
			)
			(layer "F.Fab")
		)
		(fp_line
			(start 0.120396 0.2794)
			(end -0.12065 0.2794)
			(stroke
				(width 0.1)
				(type default)
			)
			(layer "F.Fab")
		)
		(fp_line
			(start 0.120396 0.3048)
			(end 0.120396 0.2794)
			(stroke
				(width 0.1)
				(type default)
			)
			(layer "F.Fab")
		)
		(fp_line
			(start 0.12065 -0.3048)
			(end 0.67945 -0.3048)
			(stroke
				(width 0.1)
				(type default)
			)
			(layer "F.Fab")
		)
		(fp_line
			(start 0.12065 -0.2794)
			(end 0.12065 -0.3048)
			(stroke
				(width 0.1)
				(type default)
			)
			(layer "F.Fab")
		)
		(fp_line
			(start 0.67945 -0.3048)
			(end 0.67945 0.3048)
			(stroke
				(width 0.1)
				(type default)
			)
			(layer "F.Fab")
		)
		(fp_line
			(start 0.67945 0.3048)
			(end 0.120396 0.3048)
			(stroke
				(width 0.1)
				(type default)
			)
			(layer "F.Fab")
		)
		(pad "1" smd circle
			(at -0.40005 0)
			(size 0 0)
			(layers "F.Cu" "F.Mask" "F.Paste")
			(net "SMB_BMC_ALERT3_N")
		)
		(pad "2" smd circle
			(at 0.40005 0)
			(size 0 0)
			(layers "F.Cu" "F.Mask" "F.Paste")
			(net "SMB_BMC_ALERT3_R_N")
		)
	)
	(footprint ""
		(layer "F.Cu")
		(at 56.5912 -95.95485 -90)
		(property "Reference" "R497"
			(at 0 0 270)
			(layer "F.SilkS")
			(hide yes)
			(effects
				(font
					(size 1.27 1.27)
				)
			)
		)
		(property "Value" ""
			(at 0 0 270)
			(layer "F.Fab")
			(effects
				(font
					(size 1.27 1.27)
				)
			)
		)
		(duplicate_pad_numbers_are_jumpers no)
		(fp_line
			(start -0.7874 0.4064)
			(end -0.7874 -0.4064)
			(stroke
				(width 0.1524)
				(type default)
			)
			(layer "F.SilkS")
		)
		(fp_line
			(start 0.7874 0.4064)
			(end -0.7874 0.4064)
			(stroke
				(width 0.1524)
				(type default)
			)
			(layer "F.SilkS")
		)
		(fp_line
			(start -0.7874 -0.4064)
			(end 0.7874 -0.4064)
			(stroke
				(width 0.1524)
				(type default)
			)
			(layer "F.SilkS")
		)
		(fp_line
			(start 0.7874 -0.4064)
			(end 0.7874 0.4064)
			(stroke
				(width 0.1524)
				(type default)
			)
			(layer "F.SilkS")
		)
		(fp_line
			(start -0.67945 0.3048)
			(end -0.67945 -0.305054)
			(stroke
				(width 0.1)
				(type default)
			)
			(layer "F.Fab")
		)
		(fp_line
			(start -0.12065 0.3048)
			(end -0.67945 0.3048)
			(stroke
				(width 0.1)
				(type default)
			)
			(layer "F.Fab")
		)
		(fp_line
			(start 0.120396 0.3048)
			(end 0.120396 0.2794)
			(stroke
				(width 0.1)
				(type default)
			)
			(layer "F.Fab")
		)
		(fp_line
			(start 0.67945 0.3048)
			(end 0.120396 0.3048)
			(stroke
				(width 0.1)
				(type default)
			)
			(layer "F.Fab")
		)
		(fp_line
			(start -0.12065 0.2794)
			(end -0.12065 0.3048)
			(stroke
				(width 0.1)
				(type default)
			)
			(layer "F.Fab")
		)
		(fp_line
			(start 0.120396 0.2794)
			(end -0.12065 0.2794)
			(stroke
				(width 0.1)
				(type default)
			)
			(layer "F.Fab")
		)
		(fp_line
			(start -0.12065 -0.2794)
			(end 0.12065 -0.2794)
			(stroke
				(width 0.1)
				(type default)
			)
			(layer "F.Fab")
		)
		(fp_line
			(start 0.12065 -0.2794)
			(end 0.12065 -0.3048)
			(stroke
				(width 0.1)
				(type default)
			)
			(layer "F.Fab")
		)
		(fp_line
			(start 0.12065 -0.3048)
			(end 0.67945 -0.3048)
			(stroke
				(width 0.1)
				(type default)
			)
			(layer "F.Fab")
		)
		(fp_line
			(start 0.67945 -0.3048)
			(end 0.67945 0.3048)
			(stroke
				(width 0.1)
				(type default)
			)
			(layer "F.Fab")
		)
		(fp_line
			(start -0.67945 -0.305054)
			(end -0.12065 -0.305054)
			(stroke
				(width 0.1)
				(type default)
			)
			(layer "F.Fab")
		)
		(fp_line
			(start -0.12065 -0.305054)
			(end -0.12065 -0.2794)
			(stroke
				(width 0.1)
				(type default)
			)
			(layer "F.Fab")
		)
		(pad "1" smd circle
			(at -0.40005 0 270)
			(size 0 0)
			(layers "F.Cu" "F.Mask" "F.Paste")
			(net "P3V3_AUX")
		)
		(pad "2" smd circle
			(at 0.40005 0 270)
			(size 0 0)
			(layers "F.Cu" "F.Mask" "F.Paste")
			(net "IRQ_PCH_TPM_SPI_N")
		)
	)
	(footprint ""
		(layer "F.Cu")
		(at 41.9608 -81.026 90)
		(property "Reference" "R553"
			(at 0 0 90)
			(layer "F.SilkS")
			(hide yes)
			(effects
				(font
					(size 1.27 1.27)
				)
			)
		)
		(property "Value" ""
			(at 0 0 90)
			(layer "F.Fab")
			(effects
				(font
					(size 1.27 1.27)
				)
			)
		)
		(duplicate_pad_numbers_are_jumpers no)
		(fp_line
			(start 0.7874 -0.4064)
			(end 0.7874 0.4064)
			(stroke
				(width 0.1524)
				(type default)
			)
			(layer "F.SilkS")
		)
		(fp_line
			(start -0.7874 -0.4064)
			(end 0.7874 -0.4064)
			(stroke
				(width 0.1524)
				(type default)
			)
			(layer "F.SilkS")
		)
		(fp_line
			(start 0.7874 0.4064)
			(end -0.7874 0.4064)
			(stroke
				(width 0.1524)
				(type default)
			)
			(layer "F.SilkS")
		)
		(fp_line
			(start -0.7874 0.4064)
			(end -0.7874 -0.4064)
			(stroke
				(width 0.1524)
				(type default)
			)
			(layer "F.SilkS")
		)
		(fp_line
			(start -0.12065 -0.305054)
			(end -0.12065 -0.2794)
			(stroke
				(width 0.1)
				(type default)
			)
			(layer "F.Fab")
		)
		(fp_line
			(start -0.67945 -0.305054)
			(end -0.12065 -0.305054)
			(stroke
				(width 0.1)
				(type default)
			)
			(layer "F.Fab")
		)
		(fp_line
			(start 0.67945 -0.3048)
			(end 0.67945 0.3048)
			(stroke
				(width 0.1)
				(type default)
			)
			(layer "F.Fab")
		)
		(fp_line
			(start 0.12065 -0.3048)
			(end 0.67945 -0.3048)
			(stroke
				(width 0.1)
				(type default)
			)
			(layer "F.Fab")
		)
		(fp_line
			(start 0.12065 -0.2794)
			(end 0.12065 -0.3048)
			(stroke
				(width 0.1)
				(type default)
			)
			(layer "F.Fab")
		)
		(fp_line
			(start -0.12065 -0.2794)
			(end 0.12065 -0.2794)
			(stroke
				(width 0.1)
				(type default)
			)
			(layer "F.Fab")
		)
		(fp_line
			(start 0.120396 0.2794)
			(end -0.12065 0.2794)
			(stroke
				(width 0.1)
				(type default)
			)
			(layer "F.Fab")
		)
		(fp_line
			(start -0.12065 0.2794)
			(end -0.12065 0.3048)
			(stroke
				(width 0.1)
				(type default)
			)
			(layer "F.Fab")
		)
		(fp_line
			(start 0.67945 0.3048)
			(end 0.120396 0.3048)
			(stroke
				(width 0.1)
				(type default)
			)
			(layer "F.Fab")
		)
		(fp_line
			(start 0.120396 0.3048)
			(end 0.120396 0.2794)
			(stroke
				(width 0.1)
				(type default)
			)
			(layer "F.Fab")
		)
		(fp_line
			(start -0.12065 0.3048)
			(end -0.67945 0.3048)
			(stroke
				(width 0.1)
				(type default)
			)
			(layer "F.Fab")
		)
		(fp_line
			(start -0.67945 0.3048)
			(end -0.67945 -0.305054)
			(stroke
				(width 0.1)
				(type default)
			)
			(layer "F.Fab")
		)
		(pad "1" smd circle
			(at -0.40005 0 90)
			(size 0 0)
			(layers "F.Cu" "F.Mask" "F.Paste")
			(net "SPI_BMC_CS0_FLASH_R_N")
		)
		(pad "2" smd circle
			(at 0.40005 0 90)
			(size 0 0)
			(layers "F.Cu" "F.Mask" "F.Paste")
			(net "SPI_BMC_BOOT_CS0_R_N")
		)
	)
	(footprint ""
		(layer "F.Cu")
		(at 10.287 -94.615 90)
		(property "Reference" "R515"
			(at 0 0 90)
			(layer "F.SilkS")
			(hide yes)
			(effects
				(font
					(size 1.27 1.27)
				)
			)
		)
		(property "Value" ""
			(at 0 0 90)
			(layer "F.Fab")
			(effects
				(font
					(size 1.27 1.27)
				)
			)
		)
		(duplicate_pad_numbers_are_jumpers no)
		(fp_line
			(start 0.7874 -0.4064)
			(end 0.7874 0.4064)
			(stroke
				(width 0.1524)
				(type default)
			)
			(layer "F.SilkS")
		)
		(fp_line
			(start -0.7874 -0.4064)
			(end 0.7874 -0.4064)
			(stroke
				(width 0.1524)
				(type default)
			)
			(layer "F.SilkS")
		)
		(fp_line
			(start 0.7874 0.4064)
			(end -0.7874 0.4064)
			(stroke
				(width 0.1524)
				(type default)
			)
			(layer "F.SilkS")
		)
		(fp_line
			(start -0.7874 0.4064)
			(end -0.7874 -0.4064)
			(stroke
				(width 0.1524)
				(type default)
			)
			(layer "F.SilkS")
		)
		(fp_line
			(start -0.12065 -0.305054)
			(end -0.12065 -0.2794)
			(stroke
				(width 0.1)
				(type default)
			)
			(layer "F.Fab")
		)
		(fp_line
			(start -0.67945 -0.305054)
			(end -0.12065 -0.305054)
			(stroke
				(width 0.1)
				(type default)
			)
			(layer "F.Fab")
		)
		(fp_line
			(start 0.67945 -0.3048)
			(end 0.67945 0.3048)
			(stroke
				(width 0.1)
				(type default)
			)
			(layer "F.Fab")
		)
		(fp_line
			(start 0.12065 -0.3048)
			(end 0.67945 -0.3048)
			(stroke
				(width 0.1)
				(type default)
			)
			(layer "F.Fab")
		)
		(fp_line
			(start 0.12065 -0.2794)
			(end 0.12065 -0.3048)
			(stroke
				(width 0.1)
				(type default)
			)
			(layer "F.Fab")
		)
		(fp_line
			(start -0.12065 -0.2794)
			(end 0.12065 -0.2794)
			(stroke
				(width 0.1)
				(type default)
			)
			(layer "F.Fab")
		)
		(fp_line
			(start 0.120396 0.2794)
			(end -0.12065 0.2794)
			(stroke
				(width 0.1)
				(type default)
			)
			(layer "F.Fab")
		)
		(fp_line
			(start -0.12065 0.2794)
			(end -0.12065 0.3048)
			(stroke
				(width 0.1)
				(type default)
			)
			(layer "F.Fab")
		)
		(fp_line
			(start 0.67945 0.3048)
			(end 0.120396 0.3048)
			(stroke
				(width 0.1)
				(type default)
			)
			(layer "F.Fab")
		)
		(fp_line
			(start 0.120396 0.3048)
			(end 0.120396 0.2794)
			(stroke
				(width 0.1)
				(type default)
			)
			(layer "F.Fab")
		)
		(fp_line
			(start -0.12065 0.3048)
			(end -0.67945 0.3048)
			(stroke
				(width 0.1)
				(type default)
			)
			(layer "F.Fab")
		)
		(fp_line
			(start -0.67945 0.3048)
			(end -0.67945 -0.305054)
			(stroke
				(width 0.1)
				(type default)
			)
			(layer "F.Fab")
		)
		(pad "1" smd circle
			(at -0.40005 0 90)
			(size 0 0)
			(layers "F.Cu" "F.Mask" "F.Paste")
			(net "JTAG_SCM_PLD_TMS")
		)
		(pad "2" smd circle
			(at 0.40005 0 90)
			(size 0 0)
			(layers "F.Cu" "F.Mask" "F.Paste")
			(net "JTAG_SCM_CONN_TMS")
		)
	)
	(footprint ""
		(layer "F.Cu")
		(at 21.209 -68.834 -90)
		(property "Reference" "R561"
			(at 0 0 270)
			(layer "F.SilkS")
			(hide yes)
			(effects
				(font
					(size 1.27 1.27)
				)
			)
		)
		(property "Value" ""
			(at 0 0 270)
			(layer "F.Fab")
			(effects
				(font
					(size 1.27 1.27)
				)
			)
		)
		(duplicate_pad_numbers_are_jumpers no)
		(fp_line
			(start -0.7874 0.4064)
			(end -0.7874 -0.4064)
			(stroke
				(width 0.1524)
				(type default)
			)
			(layer "F.SilkS")
		)
		(fp_line
			(start 0.7874 0.4064)
			(end -0.7874 0.4064)
			(stroke
				(width 0.1524)
				(type default)
			)
			(layer "F.SilkS")
		)
		(fp_line
			(start -0.7874 -0.4064)
			(end 0.7874 -0.4064)
			(stroke
				(width 0.1524)
				(type default)
			)
			(layer "F.SilkS")
		)
		(fp_line
			(start 0.7874 -0.4064)
			(end 0.7874 0.4064)
			(stroke
				(width 0.1524)
				(type default)
			)
			(layer "F.SilkS")
		)
		(fp_line
			(start -0.67945 0.3048)
			(end -0.67945 -0.305054)
			(stroke
				(width 0.1)
				(type default)
			)
			(layer "F.Fab")
		)
		(fp_line
			(start -0.12065 0.3048)
			(end -0.67945 0.3048)
			(stroke
				(width 0.1)
				(type default)
			)
			(layer "F.Fab")
		)
		(fp_line
			(start 0.120396 0.3048)
			(end 0.120396 0.2794)
			(stroke
				(width 0.1)
				(type default)
			)
			(layer "F.Fab")
		)
		(fp_line
			(start 0.67945 0.3048)
			(end 0.120396 0.3048)
			(stroke
				(width 0.1)
				(type default)
			)
			(layer "F.Fab")
		)
		(fp_line
			(start -0.12065 0.2794)
			(end -0.12065 0.3048)
			(stroke
				(width 0.1)
				(type default)
			)
			(layer "F.Fab")
		)
		(fp_line
			(start 0.120396 0.2794)
			(end -0.12065 0.2794)
			(stroke
				(width 0.1)
				(type default)
			)
			(layer "F.Fab")
		)
		(fp_line
			(start -0.12065 -0.2794)
			(end 0.12065 -0.2794)
			(stroke
				(width 0.1)
				(type default)
			)
			(layer "F.Fab")
		)
		(fp_line
			(start 0.12065 -0.2794)
			(end 0.12065 -0.3048)
			(stroke
				(width 0.1)
				(type default)
			)
			(layer "F.Fab")
		)
		(fp_line
			(start 0.12065 -0.3048)
			(end 0.67945 -0.3048)
			(stroke
				(width 0.1)
				(type default)
			)
			(layer "F.Fab")
		)
		(fp_line
			(start 0.67945 -0.3048)
			(end 0.67945 0.3048)
			(stroke
				(width 0.1)
				(type default)
			)
			(layer "F.Fab")
		)
		(fp_line
			(start -0.67945 -0.305054)
			(end -0.12065 -0.305054)
			(stroke
				(width 0.1)
				(type default)
			)
			(layer "F.Fab")
		)
		(fp_line
			(start -0.12065 -0.305054)
			(end -0.12065 -0.2794)
			(stroke
				(width 0.1)
				(type default)
			)
			(layer "F.Fab")
		)
		(pad "1" smd circle
			(at -0.40005 0 270)
			(size 0 0)
			(layers "F.Cu" "F.Mask" "F.Paste")
			(net "RST_SPI_BMC_FLASH_R2_N")
		)
		(pad "2" smd circle
			(at 0.40005 0 270)
			(size 0 0)
			(layers "F.Cu" "F.Mask" "F.Paste")
			(net "RST_SPI_FLASH_BUF_N")
		)
	)
)
